# T6G (Grand Teton) — schematic netlist excerpt (pin names and nets, part order shuffled) for the footprints in the layout excerpt that follows; sources: Cadence DE-HDL packaged netlist, KiCad conversion of 04192023_DAF0TMB3IC0_F0TG_MB_C_brd_V02_OCP.brd

R1625  Q_RES  0 5% CHIP  pkg 0402LF  page 172 : A = JTAG_TDI_R ; B = JTAG_TDI
R3730  Q_RES  2.2K 5% CHIP  pkg 0402LF  page 252 : A = P3V3_AUX ; B = SMB_LM75_2_3V3AUX_SDA

(kicad_pcb
	(version 20260206)
	(generator "pcbnew")
	(generator_version "10.0")
	(general
		(thickness 1.6)
		(legacy_teardrops no)
	)
	(paper "A4")
	(title_block
		(title "04192023_DAF0TMB3IC0_F0TG_MB_C_brd_V02_OCP.brd")
		(comment 1 "Grand Teton / footprints 298-299 of 8354")
	)
	(layers
		(0 "F.Cu" signal "TOP")
		(4 "In1.Cu" signal "GND")
		(6 "In2.Cu" signal "IN1")
		(8 "In3.Cu" signal "GND1")
		(10 "In4.Cu" signal "IN2")
		(12 "In5.Cu" signal "GND2")
		(14 "In6.Cu" signal "IN3")
		(16 "In7.Cu" signal "GND3")
		(18 "In8.Cu" signal "VCC")
		(20 "In9.Cu" signal "VCC1")
		(22 "In10.Cu" signal "GND4")
		(24 "In11.Cu" signal "IN4")
		(26 "In12.Cu" signal "GND5")
		(28 "In13.Cu" signal "IN5")
		(30 "In14.Cu" signal "GND6")
		(32 "In15.Cu" signal "IN6")
		(34 "In16.Cu" signal "GND7")
		(2 "B.Cu" signal "BOTTOM")
		(9 "F.Adhes" user "F.Adhesive")
		(11 "B.Adhes" user "B.Adhesive")
		(13 "F.Paste" user "Package Geometry/Pastemask Top")
		(15 "B.Paste" user "Package Geometry/Pastemask Bottom")
		(5 "F.SilkS" user "Ref Des/Silkscreen Top")
		(7 "B.SilkS" user "Ref Des/Silkscreen Bottom")
		(1 "F.Mask" user "Board Geometry/Soldermask Top")
		(3 "B.Mask" user "Board Geometry/Soldermask Bottom")
		(17 "Dwgs.User" user "User.Drawings")
		(19 "Cmts.User" user "User.Comments")
		(21 "Eco1.User" user "User.Eco1")
		(23 "Eco2.User" user "User.Eco2")
		(25 "Edge.Cuts" user "Board Geometry/Outline")
		(27 "Margin" user)
		(31 "F.CrtYd" user "Package Geometry/Place Bound Top")
		(29 "B.CrtYd" user "Package Geometry/Place Bound Bottom")
		(35 "F.Fab" user "Ref Des/Assembly Top")
		(33 "B.Fab" user "Ref Des/Assembly Bottom")
	)
	(footprint ""
		(layer "F.Cu")
		(at 254.592836 -114.72545)
		(property "Reference" "R3730"
			(at 0 0 0)
			(layer "F.SilkS")
			(hide yes)
			(effects
				(font
					(size 1.27 1.27)
				)
			)
		)
		(property "Value" ""
			(at 0 0 0)
			(layer "F.Fab")
			(effects
				(font
					(size 1.27 1.27)
				)
			)
		)
		(duplicate_pad_numbers_are_jumpers no)
		(fp_line
			(start -0.7874 -0.4064)
			(end 0.7874 -0.4064)
			(stroke
				(width 0.1524)
				(type default)
			)
			(layer "F.SilkS")
		)
		(fp_line
			(start -0.7874 0.4064)
			(end -0.7874 -0.4064)
			(stroke
				(width 0.1524)
				(type default)
			)
			(layer "F.SilkS")
		)
		(fp_line
			(start 0.7874 -0.4064)
			(end 0.7874 0.4064)
			(stroke
				(width 0.1524)
				(type default)
			)
			(layer "F.SilkS")
		)
		(fp_line
			(start 0.7874 0.4064)
			(end -0.7874 0.4064)
			(stroke
				(width 0.1524)
				(type default)
			)
			(layer "F.SilkS")
		)
		(fp_line
			(start -0.67945 -0.305054)
			(end -0.12065 -0.305054)
			(stroke
				(width 0.1)
				(type default)
			)
			(layer "F.Fab")
		)
		(fp_line
			(start -0.67945 0.3048)
			(end -0.67945 -0.305054)
			(stroke
				(width 0.1)
				(type default)
			)
			(layer "F.Fab")
		)
		(fp_line
			(start -0.12065 -0.305054)
			(end -0.12065 -0.2794)
			(stroke
				(width 0.1)
				(type default)
			)
			(layer "F.Fab")
		)
		(fp_line
			(start -0.12065 -0.2794)
			(end 0.12065 -0.2794)
			(stroke
				(width 0.1)
				(type default)
			)
			(layer "F.Fab")
		)
		(fp_line
			(start -0.12065 0.2794)
			(end -0.12065 0.3048)
			(stroke
				(width 0.1)
				(type default)
			)
			(layer "F.Fab")
		)
		(fp_line
			(start -0.12065 0.3048)
			(end -0.67945 0.3048)
			(stroke
				(width 0.1)
				(type default)
			)
			(layer "F.Fab")
		)
		(fp_line
			(start 0.120396 0.2794)
			(end -0.12065 0.2794)
			(stroke
				(width 0.1)
				(type default)
			)
			(layer "F.Fab")
		)
		(fp_line
			(start 0.120396 0.3048)
			(end 0.120396 0.2794)
			(stroke
				(width 0.1)
				(type default)
			)
			(layer "F.Fab")
		)
		(fp_line
			(start 0.12065 -0.3048)
			(end 0.67945 -0.3048)
			(stroke
				(width 0.1)
				(type default)
			)
			(layer "F.Fab")
		)
		(fp_line
			(start 0.12065 -0.2794)
			(end 0.12065 -0.3048)
			(stroke
				(width 0.1)
				(type default)
			)
			(layer "F.Fab")
		)
		(fp_line
			(start 0.67945 -0.3048)
			(end 0.67945 0.3048)
			(stroke
				(width 0.1)
				(type default)
			)
			(layer "F.Fab")
		)
		(fp_line
			(start 0.67945 0.3048)
			(end 0.120396 0.3048)
			(stroke
				(width 0.1)
				(type default)
			)
			(layer "F.Fab")
		)
		(pad "1" smd circle
			(at -0.40005 0)
			(size 0 0)
			(layers "F.Cu" "F.Mask" "F.Paste")
			(net "P3V3_AUX")
		)
		(pad "2" smd circle
			(at 0.40005 0)
			(size 0 0)
			(layers "F.Cu" "F.Mask" "F.Paste")
			(net "SMB_LM75_2_3V3AUX_SDA")
		)
	)
	(footprint ""
		(layer "F.Cu")
		(at 127.705104 -52.14239)
		(property "Reference" "R1625"
			(at 0 0 0)
			(layer "F.SilkS")
			(hide yes)
			(effects
				(font
					(size 1.27 1.27)
				)
			)
		)
		(property "Value" ""
			(at 0 0 0)
			(layer "F.Fab")
			(effects
				(font
					(size 1.27 1.27)
				)
			)
		)
		(duplicate_pad_numbers_are_jumpers no)
		(fp_line
			(start -0.7874 -0.4064)
			(end 0.7874 -0.4064)
			(stroke
				(width 0.1524)
				(type default)
			)
			(layer "F.SilkS")
		)
		(fp_line
			(start -0.7874 0.4064)
			(end -0.7874 -0.4064)
			(stroke
				(width 0.1524)
				(type default)
			)
			(layer "F.SilkS")
		)
		(fp_line
			(start 0.7874 -0.4064)
			(end 0.7874 0.4064)
			(stroke
				(width 0.1524)
				(type default)
			)
			(layer "F.SilkS")
		)
		(fp_line
			(start 0.7874 0.4064)
			(end -0.7874 0.4064)
			(stroke
				(width 0.1524)
				(type default)
			)
			(layer "F.SilkS")
		)
		(fp_line
			(start -0.67945 -0.305054)
			(end -0.12065 -0.305054)
			(stroke
				(width 0.1)
				(type default)
			)
			(layer "F.Fab")
		)
		(fp_line
			(start -0.67945 0.3048)
			(end -0.67945 -0.305054)
			(stroke
				(width 0.1)
				(type default)
			)
			(layer "F.Fab")
		)
		(fp_line
			(start -0.12065 -0.305054)
			(end -0.12065 -0.2794)
			(stroke
				(width 0.1)
				(type default)
			)
			(layer "F.Fab")
		)
		(fp_line
			(start -0.12065 -0.2794)
			(end 0.12065 -0.2794)
			(stroke
				(width 0.1)
				(type default)
			)
			(layer "F.Fab")
		)
		(fp_line
			(start -0.12065 0.2794)
			(end -0.12065 0.3048)
			(stroke
				(width 0.1)
				(type default)
			)
			(layer "F.Fab")
		)
		(fp_line
			(start -0.12065 0.3048)
			(end -0.67945 0.3048)
			(stroke
				(width 0.1)
				(type default)
			)
			(layer "F.Fab")
		)
		(fp_line
			(start 0.120396 0.2794)
			(end -0.12065 0.2794)
			(stroke
				(width 0.1)
				(type default)
			)
			(layer "F.Fab")
		)
		(fp_line
			(start 0.120396 0.3048)
			(end 0.120396 0.2794)
			(stroke
				(width 0.1)
				(type default)
			)
			(layer "F.Fab")
		)
		(fp_line
			(start 0.12065 -0.3048)
			(end 0.67945 -0.3048)
			(stroke
				(width 0.1)
				(type default)
			)
			(layer "F.Fab")
		)
		(fp_line
			(start 0.12065 -0.2794)
			(end 0.12065 -0.3048)
			(stroke
				(width 0.1)
				(type default)
			)
			(layer "F.Fab")
		)
		(fp_line
			(start 0.67945 -0.3048)
			(end 0.67945 0.3048)
			(stroke
				(width 0.1)
				(type default)
			)
			(layer "F.Fab")
		)
		(fp_line
			(start 0.67945 0.3048)
			(end 0.120396 0.3048)
			(stroke
				(width 0.1)
				(type default)
			)
			(layer "F.Fab")
		)
		(pad "1" smd circle
			(at -0.40005 0)
			(size 0 0)
			(layers "F.Cu" "F.Mask" "F.Paste")
			(net "JTAG_TDI_R")
		)
		(pad "2" smd circle
			(at 0.40005 0)
			(size 0 0)
			(layers "F.Cu" "F.Mask" "F.Paste")
			(net "JTAG_TDI")
		)
	)
)
